FILE_TYPE = MACRO_DRAWING;
SET COLOR_WIRE YELLOW;
SET COLOR_PROP ORANGE;
SET COLOR_DOT WHITE;
SET COLOR_ARC YELLOW;
SET COLOR_BODY GREEN;
SET COLOR_NOTE PURPLE;
SET PROP_DISPLAY VALUE;
SET PAGE_NUMBER P445;
FORCEADD QUANTA_TITLE_BLOCK_C..1
(0 0);
FORCEPROP 1 LAST CUSTOM_TXT_CDS <NAME_2>
J 0
(-3175 50);
FORCEPROP 1 LAST CUSTOM_TXT_CDS <NAME_1>
J 0
(-3175 175);
FORCEPROP 1 LAST CUSTOM_TXT_CDS <Q_NUMBER>
J 0
(-1403 103);
DISPLAY 1.212766 (-1403 103);
FORCEPROP 1 LAST CUSTOM_TXT_CDS <Q_PROJ>
J 0
(-2382 102);
DISPLAY 1.212766 (-2382 102);
FORCEPROP 1 LAST CUSTOM_TXT_CDS <Q_REV>
J 0
(-184 103);
DISPLAY 1.212766 (-184 103);
FORCEPROP 1 LAST CUSTOM_TXT_CDS <CON_LAST_MODIFIED>
J 0
(-1885 15);
DISPLAY 0.978723 (-1885 15);
FORCEPROP 1 LAST CUSTOM_TXT_CDS <CON_PAGE_NUM> OF <CON_TOTAL_PAGES>
J 0
(-446 18);
DISPLAY 0.978723 (-446 18);
FORCEPROP 1 LAST Q_TITLE RETIMER_CPU1_P1(10)
J 0
(-9366 26);
DISPLAY 2.446809 (-9366 26);
PAINT GREEN (-9366 26);
FORCEPROP 2 LAST CDS_LIB pure_quanta
J 0
(0 0);
DISPLAY INVISIBLE (0 0);
FORCEPROP 1 LAST CDS_LMAN_SYM_OUTLINE -9475,6775,100,-125
J 0
(0 0);
DISPLAY 0.468085 (0 0);
PAINT GREEN (0 0);
DISPLAY INVISIBLE (0 0);
FORCEPROP 2 LAST PAGE_BORDER TRUE
J 0
(-7890 5250);
DISPLAY 0.638298 (-7890 5250);
PAINT PINK (-7890 5250);
DISPLAY INVISIBLE (-7890 5250);
FORCEPROP 2 LAST CDS_XR_PAGE_TITLE CR-337 : @T6G_MB_LIB.T6G(SCH_1):PAGE337
J 0
(-7890 5250);
DISPLAY 0.638298 (-7890 5250);
PAINT PINK (-7890 5250);
DISPLAY INVISIBLE (-7890 5250);
FORCEPROP 2 LAST CUSTOM_TXT_CDS <XR_PAGE_TITLE>
J 0
(-7890 5250);
DISPLAY 0.638298 (-7890 5250);
PAINT PINK (-7890 5250);
DISPLAY INVISIBLE (-7890 5250);
FORCEPROP 1 LAST COMMENT_BODY TRUE
J 0
(12 -13);
DISPLAY 0.978723 (12 -13);
PAINT GREEN (12 -13);
DISPLAY INVISIBLE (12 -13);
FORCEPROP 1 LAST Q_DEPT BU9
J 1
(-3763 49);
DISPLAY 1.957447 (-3763 49);
PAINT GREEN (-3763 49);
DISPLAY INVISIBLE (-3763 49);
FORCEPROP 0 LAST CDS_CON_LAST_MODIFIED Thu Aug 24 10:16:55 2023
J 0
(-1885 15);
DISPLAY INVISIBLE (-1885 15);
QUIT
